# T6G (Grand Teton) — schematic netlist excerpt (pin names and nets, part order shuffled) for the footprints in the layout excerpt that follows; sources: Cadence DE-HDL packaged netlist, KiCad conversion of 04192023_DAF0TMB3IC0_F0TG_MB_C_brd_V02_OCP.brd

C1976  Q_CAP  0.1UF 25V 10% X7R  pkg 0402  page 126 : A = GPU_FPGA_OVERT_ISO_N ; B = GND
PR164  Q_RES  49.9 1% CHIP  pkg 0402LF  page 210 : A = VSENSE_VSS_SENSE_A_P1 ; B = GND

(kicad_pcb
	(version 20260206)
	(generator "pcbnew")
	(generator_version "10.0")
	(general
		(thickness 1.6)
		(legacy_teardrops no)
	)
	(paper "A4")
	(title_block
		(title "04192023_DAF0TMB3IC0_F0TG_MB_C_brd_V02_OCP.brd")
		(comment 1 "Grand Teton / footprints 2537-2538 of 8354")
	)
	(layers
		(0 "F.Cu" signal "TOP")
		(4 "In1.Cu" signal "GND")
		(6 "In2.Cu" signal "IN1")
		(8 "In3.Cu" signal "GND1")
		(10 "In4.Cu" signal "IN2")
		(12 "In5.Cu" signal "GND2")
		(14 "In6.Cu" signal "IN3")
		(16 "In7.Cu" signal "GND3")
		(18 "In8.Cu" signal "VCC")
		(20 "In9.Cu" signal "VCC1")
		(22 "In10.Cu" signal "GND4")
		(24 "In11.Cu" signal "IN4")
		(26 "In12.Cu" signal "GND5")
		(28 "In13.Cu" signal "IN5")
		(30 "In14.Cu" signal "GND6")
		(32 "In15.Cu" signal "IN6")
		(34 "In16.Cu" signal "GND7")
		(2 "B.Cu" signal "BOTTOM")
		(9 "F.Adhes" user "F.Adhesive")
		(11 "B.Adhes" user "B.Adhesive")
		(13 "F.Paste" user "Package Geometry/Pastemask Top")
		(15 "B.Paste" user "Package Geometry/Pastemask Bottom")
		(5 "F.SilkS" user "Ref Des/Silkscreen Top")
		(7 "B.SilkS" user "Ref Des/Silkscreen Bottom")
		(1 "F.Mask" user "Board Geometry/Soldermask Top")
		(3 "B.Mask" user "Board Geometry/Soldermask Bottom")
		(17 "Dwgs.User" user "User.Drawings")
		(19 "Cmts.User" user "User.Comments")
		(21 "Eco1.User" user "User.Eco1")
		(23 "Eco2.User" user "User.Eco2")
		(25 "Edge.Cuts" user "Board Geometry/Outline")
		(27 "Margin" user)
		(31 "F.CrtYd" user "Package Geometry/Place Bound Top")
		(29 "B.CrtYd" user "Package Geometry/Place Bound Bottom")
		(35 "F.Fab" user "Ref Des/Assembly Top")
		(33 "B.Fab" user "Ref Des/Assembly Bottom")
	)
	(footprint ""
		(layer "F.Cu")
		(at 307.404516 -435.720744 90)
		(property "Reference" "C1976"
			(at 0 0 90)
			(layer "F.SilkS")
			(hide yes)
			(effects
				(font
					(size 1.27 1.27)
				)
			)
		)
		(property "Value" ""
			(at 0 0 90)
			(layer "F.Fab")
			(effects
				(font
					(size 1.27 1.27)
				)
			)
		)
		(duplicate_pad_numbers_are_jumpers no)
		(fp_line
			(start 0.7874 -0.4064)
			(end 0.7874 0.4064)
			(stroke
				(width 0.1524)
				(type default)
			)
			(layer "F.SilkS")
		)
		(fp_line
			(start -0.7874 -0.4064)
			(end 0.7874 -0.4064)
			(stroke
				(width 0.1524)
				(type default)
			)
			(layer "F.SilkS")
		)
		(fp_line
			(start 0.7874 0.4064)
			(end -0.7874 0.4064)
			(stroke
				(width 0.1524)
				(type default)
			)
			(layer "F.SilkS")
		)
		(fp_line
			(start -0.7874 0.4064)
			(end -0.7874 -0.4064)
			(stroke
				(width 0.1524)
				(type default)
			)
			(layer "F.SilkS")
		)
		(fp_line
			(start -0.12065 -0.305054)
			(end -0.12065 -0.2794)
			(stroke
				(width 0.1)
				(type default)
			)
			(layer "F.Fab")
		)
		(fp_line
			(start -0.67945 -0.305054)
			(end -0.12065 -0.305054)
			(stroke
				(width 0.1)
				(type default)
			)
			(layer "F.Fab")
		)
		(fp_line
			(start 0.67945 -0.3048)
			(end 0.67945 0.3048)
			(stroke
				(width 0.1)
				(type default)
			)
			(layer "F.Fab")
		)
		(fp_line
			(start 0.12065 -0.3048)
			(end 0.67945 -0.3048)
			(stroke
				(width 0.1)
				(type default)
			)
			(layer "F.Fab")
		)
		(fp_line
			(start 0.12065 -0.2794)
			(end 0.12065 -0.3048)
			(stroke
				(width 0.1)
				(type default)
			)
			(layer "F.Fab")
		)
		(fp_line
			(start -0.12065 -0.2794)
			(end 0.12065 -0.2794)
			(stroke
				(width 0.1)
				(type default)
			)
			(layer "F.Fab")
		)
		(fp_line
			(start 0.120396 0.2794)
			(end -0.12065 0.2794)
			(stroke
				(width 0.1)
				(type default)
			)
			(layer "F.Fab")
		)
		(fp_line
			(start -0.12065 0.2794)
			(end -0.12065 0.3048)
			(stroke
				(width 0.1)
				(type default)
			)
			(layer "F.Fab")
		)
		(fp_line
			(start 0.67945 0.3048)
			(end 0.120396 0.3048)
			(stroke
				(width 0.1)
				(type default)
			)
			(layer "F.Fab")
		)
		(fp_line
			(start 0.120396 0.3048)
			(end 0.120396 0.2794)
			(stroke
				(width 0.1)
				(type default)
			)
			(layer "F.Fab")
		)
		(fp_line
			(start -0.12065 0.3048)
			(end -0.67945 0.3048)
			(stroke
				(width 0.1)
				(type default)
			)
			(layer "F.Fab")
		)
		(fp_line
			(start -0.67945 0.3048)
			(end -0.67945 -0.305054)
			(stroke
				(width 0.1)
				(type default)
			)
			(layer "F.Fab")
		)
		(pad "1" smd circle
			(at -0.40005 0 90)
			(size 0 0)
			(layers "F.Cu" "F.Mask" "F.Paste")
			(net "GPU_FPGA_OVERT_ISO_N")
		)
		(pad "2" smd circle
			(at 0.40005 0 90)
			(size 0 0)
			(layers "F.Cu" "F.Mask" "F.Paste")
			(net "GND")
		)
	)
	(footprint ""
		(layer "F.Cu")
		(at 138.617198 -167.510206 180)
		(property "Reference" "PR164"
			(at 0 0 180)
			(layer "F.SilkS")
			(hide yes)
			(effects
				(font
					(size 1.27 1.27)
				)
			)
		)
		(property "Value" ""
			(at 0 0 180)
			(layer "F.Fab")
			(effects
				(font
					(size 1.27 1.27)
				)
			)
		)
		(duplicate_pad_numbers_are_jumpers no)
		(fp_line
			(start 0.7874 0.4064)
			(end -0.7874 0.4064)
			(stroke
				(width 0.1524)
				(type default)
			)
			(layer "F.SilkS")
		)
		(fp_line
			(start 0.7874 -0.4064)
			(end 0.7874 0.4064)
			(stroke
				(width 0.1524)
				(type default)
			)
			(layer "F.SilkS")
		)
		(fp_line
			(start -0.7874 0.4064)
			(end -0.7874 -0.4064)
			(stroke
				(width 0.1524)
				(type default)
			)
			(layer "F.SilkS")
		)
		(fp_line
			(start -0.7874 -0.4064)
			(end 0.7874 -0.4064)
			(stroke
				(width 0.1524)
				(type default)
			)
			(layer "F.SilkS")
		)
		(fp_line
			(start 0.67945 0.3048)
			(end 0.120396 0.3048)
			(stroke
				(width 0.1)
				(type default)
			)
			(layer "F.Fab")
		)
		(fp_line
			(start 0.67945 -0.3048)
			(end 0.67945 0.3048)
			(stroke
				(width 0.1)
				(type default)
			)
			(layer "F.Fab")
		)
		(fp_line
			(start 0.12065 -0.2794)
			(end 0.12065 -0.3048)
			(stroke
				(width 0.1)
				(type default)
			)
			(layer "F.Fab")
		)
		(fp_line
			(start 0.12065 -0.3048)
			(end 0.67945 -0.3048)
			(stroke
				(width 0.1)
				(type default)
			)
			(layer "F.Fab")
		)
		(fp_line
			(start 0.120396 0.3048)
			(end 0.120396 0.2794)
			(stroke
				(width 0.1)
				(type default)
			)
			(layer "F.Fab")
		)
		(fp_line
			(start 0.120396 0.2794)
			(end -0.12065 0.2794)
			(stroke
				(width 0.1)
				(type default)
			)
			(layer "F.Fab")
		)
		(fp_line
			(start -0.12065 0.3048)
			(end -0.67945 0.3048)
			(stroke
				(width 0.1)
				(type default)
			)
			(layer "F.Fab")
		)
		(fp_line
			(start -0.12065 0.2794)
			(end -0.12065 0.3048)
			(stroke
				(width 0.1)
				(type default)
			)
			(layer "F.Fab")
		)
		(fp_line
			(start -0.12065 -0.2794)
			(end 0.12065 -0.2794)
			(stroke
				(width 0.1)
				(type default)
			)
			(layer "F.Fab")
		)
		(fp_line
			(start -0.12065 -0.305054)
			(end -0.12065 -0.2794)
			(stroke
				(width 0.1)
				(type default)
			)
			(layer "F.Fab")
		)
		(fp_line
			(start -0.67945 0.3048)
			(end -0.67945 -0.305054)
			(stroke
				(width 0.1)
				(type default)
			)
			(layer "F.Fab")
		)
		(fp_line
			(start -0.67945 -0.305054)
			(end -0.12065 -0.305054)
			(stroke
				(width 0.1)
				(type default)
			)
			(layer "F.Fab")
		)
		(pad "1" smd circle
			(at -0.40005 0 180)
			(size 0 0)
			(layers "F.Cu" "F.Mask" "F.Paste")
			(net "VSENSE_VSS_SENSE_A_P1")
		)
		(pad "2" smd circle
			(at 0.40005 0 180)
			(size 0 0)
			(layers "F.Cu" "F.Mask" "F.Paste")
			(net "GND")
		)
	)
)
